#ISCELL
  mstr_misc dns *
  *
#ISCELL
  mstr_symbols bom_note *
  *
#ISCELL
  mstr_symbols cad_note *
  *
#ISCELL
  mstr_symbols design_note *
  *
#ISCELL
  mstr_symbols intel_corp_bpage *
  *
#CELL
  mstr_analog nc7sb3157 *
  page113_i107
#ISCELL
  mstr_symbols gnd *
  page113_i109
#ISCELL
  mstr_symbols gnd *
  page113_i110
#ISCELL
  mstr_standard offpage *
  page113_i111
#ISCELL
  mstr_standard offpage *
  page113_i112
#ISCELL
  mstr_standard offpage *
  page113_i113
#CELL
  dev_discrete cap_a *
  page113_i116
#CELL
  dev_discrete cap_a *
  page113_i117
#ISCELL
  mstr_symbols gnd *
  page113_i118
#CELL
  dev_discrete cap_a *
  page113_i119
#ISCELL
  mstr_symbols gnd *
  page113_i121
#ISCELL
  mstr_standard offpage *
  page113_i124
#ISCELL
  mstr_standard offpage *
  page113_i126
#CELL
  mstr_ttl 74cbtlv1g125 *
  page113_i127
#ISCELL
  mstr_standard offpage *
  page113_i128
#ISCELL
  mstr_standard offpage *
  page113_i143
#ISCELL
  mstr_symbols gnd *
  page113_i146
#CELL
  dev_discrete cap_a *
  page113_i147
#ISCELL
  mstr_standard offpage *
  page113_i153
#ISCELL
  mstr_standard offpage *
  page113_i154
#ISCELL
  mstr_standard offpage *
  page113_i155
#ISCELL
  mstr_symbols p3v3_stby *
  page113_i160
#ISCELL
  mstr_symbols p3v3_stby *
  page113_i161
#ISCELL
  mstr_standard offpage *
  page113_i162
#ISCELL
  mstr_standard offpage *
  page113_i163
#CELL
  mstr_discrete res *
  page113_i168
#ISCELL
  mstr_standard offpage *
  page113_i169
#ISCELL
  mstr_symbols vcc_core *
  page113_i171
#ISCELL
  mstr_standard offpage *
  page113_i172
#CELL
  mstr_sconn sconn10_c12536004 *
  page113_i175
#ISCELL
  mstr_standard offpage *
  page113_i176
#CELL
  mstr_discrete res *
  page113_i179
#CELL
  mstr_discrete res *
  page113_i180
#ISCELL
  mstr_symbols gnd *
  page113_i182
#CELL
  mstr_ttl 74cbtlv1g125 *
  page113_i185
#ISCELL
  mstr_symbols gnd *
  page113_i186
#CELL
  mstr_ttl 74cbtlv1g125 *
  page113_i190
#ISCELL
  mstr_standard offpage *
  page113_i192
#ISCELL
  mstr_standard offpage *
  page113_i193
#CELL
  mstr_discrete res *
  page113_i195
#CELL
  mstr_ttl 74cbtlv1g125 *
  page113_i196
#ISCELL
  mstr_standard offpage *
  page113_i197
#CELL
  mstr_discrete res *
  page113_i199
#ISCELL
  mstr_symbols gnd *
  page113_i200
#ISCELL
  mstr_symbols vcc_core *
  page113_i201
#CELL
  mstr_discrete res *
  page113_i202
#CELL
  mstr_discrete res *
  page113_i203
#CELL
  mstr_discrete res *
  page113_i204
#CELL
  mstr_discrete res *
  page113_i205
#CELL
  mstr_ttl 74cbtlv1g125 *
  page113_i206
#ISCELL
  mstr_standard offpage *
  page113_i212
#ISCELL
  mstr_standard offpage *
  page113_i213
#ISCELL
  mstr_standard offpage *
  page113_i214
#ISCELL
  mstr_standard offpage *
  page113_i215
#ISCELL
  mstr_symbols vcc_core *
  page113_i236
#ISCELL
  mstr_standard offpage *
  page113_i238
#CELL
  mstr_discrete res *
  page113_i239
#CELL
  mstr_discrete res *
  page113_i240
#ISCELL
  mstr_symbols vcc_core *
  page113_i241
#ISCELL
  mstr_standard offpage *
  page113_i242
#ISCELL
  mstr_standard offpage *
  page113_i243
#ISCELL
  mstr_standard offpage *
  page113_i244
#ISCELL
  mstr_symbols vcc_core *
  page113_i245
#CELL
  dev_discrete cap_a *
  page113_i246
#ISCELL
  mstr_symbols gnd *
  page113_i247
#CELL
  dev_discrete cap_a *
  page113_i248
#ISCELL
  mstr_symbols gnd *
  page113_i249
#CELL
  dev_discrete cap_a *
  page113_i250
#ISCELL
  mstr_symbols gnd *
  page113_i251
#CELL
  mstr_analog nc7sb3157 *
  page113_i255
#ISCELL
  mstr_standard offpage *
  page113_i256
#ISCELL
  mstr_standard offpage *
  page113_i257
#ISCELL
  mstr_standard offpage *
  page113_i258
#ISCELL
  mstr_symbols p3v3_stby *
  page113_i259
#ISCELL
  mstr_symbols gnd *
  page113_i261
#ISCELL
  mstr_symbols gnd *
  page113_i263
#ISCELL
  mstr_standard offpage *
  page113_i264
#CELL
  dev_discrete cap_a *
  page113_i265
#CELL
  dev_discrete cap_a *
  page113_i266
#CELL
  dev_discrete cap_a *
  page113_i267
#ISCELL
  mstr_symbols gnd *
  page113_i268
#ISCELL
  mstr_symbols p3v3_stby *
  page113_i269
#CELL
  mstr_discrete res *
  page113_i270
#CELL
  mstr_discrete res *
  page113_i271
#CELL
  mstr_discrete res *
  page113_i272
#CELL
  mstr_discrete res *
  page113_i273
